(kicad_pcb
	(version 20241229)
	(generator "pcbnew")
	(generator_version "9.0")
	(general
		(thickness 1.711)
		(legacy_teardrops no)
	)
	(paper "A4")
	(title_block
		(title "Antmicro Baseboard for Jetson AGX Thor")
		(date "2026-02-18")
		(rev "1.1.0")
		(company "Antmicro Ltd")
		(comment 1 "www.antmicro.com")
		(comment 9 "footprints 509-513 of 1170")
	)
	(layers
		(0 "F.Cu" signal)
		(4 "In1.Cu" signal)
		(6 "In2.Cu" signal)
		(8 "In3.Cu" signal)
		(10 "In4.Cu" jumper)
		(12 "In5.Cu" signal)
		(14 "In6.Cu" signal)
		(16 "In7.Cu" signal)
		(18 "In8.Cu" signal)
		(2 "B.Cu" signal)
		(9 "F.Adhes" user "F.Adhesive")
		(11 "B.Adhes" user "B.Adhesive")
		(13 "F.Paste" user)
		(15 "B.Paste" user)
		(5 "F.SilkS" user "F.Silkscreen")
		(7 "B.SilkS" user "B.Silkscreen")
		(1 "F.Mask" user)
		(3 "B.Mask" user)
		(17 "Dwgs.User" user "User.Drawings")
		(19 "Cmts.User" user "User.Comments")
		(21 "Eco1.User" user "User.Eco1")
		(23 "Eco2.User" user "User.Eco2")
		(25 "Edge.Cuts" user)
		(27 "Margin" user)
		(31 "F.CrtYd" user "F.Courtyard")
		(29 "B.CrtYd" user "B.Courtyard")
		(35 "F.Fab" user)
		(33 "B.Fab" user)
	)
	(footprint "antmicro-footprints:Fiducial_1mm_Mask3mm"
		(layer "F.Cu")
		(at 224.69 134.79)
		(descr "Circular Fiducial, 1.5mm bare copper, 3mm soldermask opening")
		(tags "fiducial")
		(property "Reference" "FD3"
			(at 1.31 1.59 0)
			(layer "F.SilkS")
			(effects
				(font
					(size 0.7 0.7)
					(thickness 0.15)
				)
				(justify left bottom)
			)
		)
		(property "Value" "Fiducial_1mm_Mask3mm"
			(at 0 2.603 0)
			(layer "F.Fab")
			(effects
				(font
					(size 0.7 0.7)
					(thickness 0.15)
				)
				(justify left bottom)
			)
		)
		(property "Description" "Fiducial mask"
			(at 0 0 0)
			(layer "F.Fab")
			(hide yes)
			(effects
				(font
					(size 1.27 1.27)
					(thickness 0.15)
				)
			)
		)
		(property "Author" "Antmicro"
			(at 0 0 0)
			(unlocked yes)
			(layer "F.Fab")
			(hide yes)
			(effects
				(font
					(size 1 1)
					(thickness 0.15)
				)
			)
		)
		(property "License" "Apache-2.0"
			(at 0 0 0)
			(unlocked yes)
			(layer "F.Fab")
			(hide yes)
			(effects
				(font
					(size 1 1)
					(thickness 0.15)
				)
			)
		)
		(sheetname "/")
		(sheetfile "jetson-agx-thor-baseboard.kicad_sch")
		(attr exclude_from_pos_files exclude_from_bom)
		(fp_circle
			(center 0 0)
			(end 1.5 0)
			(stroke
				(width 0.05)
				(type solid)
			)
			(fill no)
			(layer "F.CrtYd")
		)
		(fp_circle
			(center 0 0)
			(end 1.5 0)
			(stroke
				(width 0.15)
				(type solid)
			)
			(fill no)
			(layer "F.Fab")
		)
		(fp_text user "${REFERENCE}"
			(at -1.25 4.603 0)
			(layer "F.Fab")
			(effects
				(font
					(size 0.7 0.7)
					(thickness 0.15)
				)
				(justify left bottom)
			)
		)
		(fp_text user "Author: Antmicro"
			(at -1.25 5.803 0)
			(layer "F.Fab")
			(effects
				(font
					(size 0.7 0.7)
					(thickness 0.15)
				)
				(justify left bottom)
			)
		)
		(fp_text user "License: Apache-2.0"
			(at -1.25 7.003 0)
			(layer "F.Fab")
			(effects
				(font
					(size 0.7 0.7)
					(thickness 0.15)
				)
				(justify left bottom)
			)
		)
		(pad "" smd circle
			(at 0 0)
			(size 1 1)
			(layers "F.Cu" "F.Mask")
			(solder_mask_margin 1)
			(clearance 1)
		)
	)
	(footprint "antmicro-footprints:C_0402_1005Metric"
		(layer "F.Cu")
		(at 212.8 63.68 -90)
		(descr "Capacitor SMD 0402")
		(tags "capacitor SMD 0402")
		(property "Reference" "C357"
			(at -3.63 0.24 270)
			(layer "F.SilkS")
			(effects
				(font
					(size 0.7 0.7)
					(thickness 0.15)
				)
				(justify right top)
			)
		)
		(property "Value" "C_100n_0402"
			(at -1.022927 2.155213 90)
			(layer "F.Fab")
			(effects
				(font
					(size 0.7 0.7)
					(thickness 0.15)
				)
				(justify right top)
			)
		)
		(property "Datasheet" "https://www.murata.com/products/productdetail?partno=GRM155R61H104KE14%23"
			(at 0 0 90)
			(layer "F.Fab")
			(hide yes)
			(effects
				(font
					(size 1.27 1.27)
					(thickness 0.15)
				)
			)
		)
		(property "Description" "SMD Multilayer Ceramic Capacitor, 0.1 µF, 50 V, 0402 [1005 Metric], ± 10%, X5R, GRM Series"
			(at 0 0 90)
			(layer "F.Fab")
			(hide yes)
			(effects
				(font
					(size 1.27 1.27)
					(thickness 0.15)
				)
			)
		)
		(property "MPN" "GRM155R61H104KE14D"
			(at 0 0 270)
			(unlocked yes)
			(layer "F.Fab")
			(hide yes)
			(effects
				(font
					(size 1 1)
					(thickness 0.15)
				)
			)
		)
		(property "Val" "100n"
			(at 0 0 270)
			(unlocked yes)
			(layer "F.Fab")
			(hide yes)
			(effects
				(font
					(size 1 1)
					(thickness 0.15)
				)
			)
		)
		(property "Voltage" "50V"
			(at 0 0 270)
			(unlocked yes)
			(layer "F.Fab")
			(hide yes)
			(effects
				(font
					(size 1 1)
					(thickness 0.15)
				)
			)
		)
		(property "Dielectric" "X5R"
			(at 0 0 270)
			(unlocked yes)
			(layer "F.Fab")
			(hide yes)
			(effects
				(font
					(size 1 1)
					(thickness 0.15)
				)
			)
		)
		(property "Manufacturer" "Murata"
			(at 0 0 270)
			(unlocked yes)
			(layer "F.Fab")
			(hide yes)
			(effects
				(font
					(size 1 1)
					(thickness 0.15)
				)
			)
		)
		(property "License" "Apache-2.0"
			(at 0 0 270)
			(unlocked yes)
			(layer "F.Fab")
			(hide yes)
			(effects
				(font
					(size 1 1)
					(thickness 0.15)
				)
			)
		)
		(property "Author" "Antmicro"
			(at 0 0 270)
			(unlocked yes)
			(layer "F.Fab")
			(hide yes)
			(effects
				(font
					(size 1 1)
					(thickness 0.15)
				)
			)
		)
		(sheetname "/Power/")
		(sheetfile "power.kicad_sch")
		(attr smd)
		(fp_rect
			(start -0.925 -0.47)
			(end 0.925 0.47)
			(stroke
				(width 0.05)
				(type default)
			)
			(fill no)
			(layer "F.CrtYd")
		)
		(fp_line
			(start -0.494 0.248)
			(end -0.494 -0.25)
			(stroke
				(width 0.15)
				(type solid)
			)
			(layer "F.Fab")
		)
		(fp_line
			(start 0.504 0.248)
			(end -0.494 0.248)
			(stroke
				(width 0.15)
				(type solid)
			)
			(layer "F.Fab")
		)
		(fp_line
			(start -0.494 -0.25)
			(end 0.504 -0.25)
			(stroke
				(width 0.15)
				(type solid)
			)
			(layer "F.Fab")
		)
		(fp_line
			(start 0.504 -0.25)
			(end 0.504 0.248)
			(stroke
				(width 0.15)
				(type solid)
			)
			(layer "F.Fab")
		)
		(fp_text user "Author: Antmicro"
			(at -0.939 3.399 90)
			(layer "F.Fab")
			(effects
				(font
					(size 0.7 0.7)
					(thickness 0.15)
				)
				(justify right top)
			)
		)
		(fp_text user "${REFERENCE}"
			(at -0.939 4.599 90)
			(layer "F.Fab")
			(effects
				(font
					(size 0.7 0.7)
					(thickness 0.15)
				)
				(justify right top)
			)
		)
		(fp_text user "License: Apache-2.0"
			(at -0.939 5.799 90)
			(layer "F.Fab")
			(effects
				(font
					(size 0.7 0.7)
					(thickness 0.15)
				)
				(justify right top)
			)
		)
		(pad "1" smd roundrect
			(at -0.48 0 270)
			(size 0.59 0.64)
			(layers "F.Cu" "F.Mask" "F.Paste")
			(roundrect_rratio 0.25)
			(net 1 "GND")
			(pintype "passive")
		)
		(pad "2" smd roundrect
			(at 0.48 0 270)
			(size 0.59 0.64)
			(layers "F.Cu" "F.Mask" "F.Paste")
			(roundrect_rratio 0.25)
			(net 1383 "VCC_NO_OVP")
			(pintype "passive")
		)
	)
	(footprint "antmicro-footprints:Conn_JST_SH_1x4_BM04B-SRSS-TB-LF-SN"
		(layer "F.Cu")
		(at 200.15 111.6 180)
		(property "Reference" "J21"
			(at -1.75 -3.3 0)
			(layer "F.SilkS")
			(effects
				(font
					(size 0.7 0.7)
					(thickness 0.15)
				)
				(justify right top)
			)
		)
		(property "Value" "JST_SH_1x4_BM04B-SRSS-TB-LF-SN"
			(at -3.25 5 0)
			(layer "F.Fab")
			(effects
				(font
					(size 0.7 0.7)
					(thickness 0.15)
				)
				(justify right top)
			)
		)
		(property "Datasheet" "https://www.jst-mfg.com/product/pdf/eng/eSH.pdf"
			(at 0 0 0)
			(layer "F.Fab")
			(hide yes)
			(effects
				(font
					(size 1.27 1.27)
					(thickness 0.15)
				)
			)
		)
		(property "Description" "Pin Header, Top Entry, Wire-to-Board, 1 mm, 1 Rows, 4 Contacts, Surface Mount, SR"
			(at 0 0 0)
			(layer "F.Fab")
			(hide yes)
			(effects
				(font
					(size 1.27 1.27)
					(thickness 0.15)
				)
			)
		)
		(property "MPN" "BM04B-SRSS-TB(LF)(SN) "
			(at 0 0 180)
			(unlocked yes)
			(layer "F.Fab")
			(hide yes)
			(effects
				(font
					(size 1 1)
					(thickness 0.15)
				)
			)
		)
		(property "Manufacturer" "JST Automotive Connectors"
			(at 0 0 180)
			(unlocked yes)
			(layer "F.Fab")
			(hide yes)
			(effects
				(font
					(size 1 1)
					(thickness 0.15)
				)
			)
		)
		(property "Author" "Antmicro"
			(at 0 0 180)
			(unlocked yes)
			(layer "F.Fab")
			(hide yes)
			(effects
				(font
					(size 1 1)
					(thickness 0.15)
				)
			)
		)
		(property "License" "Apache-2.0"
			(at 0 0 180)
			(unlocked yes)
			(layer "F.Fab")
			(hide yes)
			(effects
				(font
					(size 1 1)
					(thickness 0.15)
				)
			)
		)
		(sheetname "/SoM_Power/")
		(sheetfile "som_power.kicad_sch")
		(attr smd exclude_from_pos_files exclude_from_bom dnp)
		(fp_line
			(start 1.774 -1.7)
			(end 1.774 1.702)
			(stroke
				(width 0.15)
				(type solid)
			)
			(layer "F.SilkS")
		)
		(fp_line
			(start -0.251 2.999)
			(end -1.125 2.999)
			(stroke
				(width 0.15)
				(type solid)
			)
			(layer "F.SilkS")
		)
		(fp_line
			(start -0.251 -2.999)
			(end -1.125 -2.999)
			(stroke
				(width 0.15)
				(type solid)
			)
			(layer "F.SilkS")
		)
		(fp_line
			(start -1.125 2.999)
			(end -1.125 2.201)
			(stroke
				(width 0.15)
				(type solid)
			)
			(layer "F.SilkS")
		)
		(fp_line
			(start -1.125 -2.999)
			(end -1.125 -2.201)
			(stroke
				(width 0.15)
				(type solid)
			)
			(layer "F.SilkS")
		)
		(fp_circle
			(center -1.6 -2.1)
			(end -1.55 -2.1)
			(stroke
				(width 0.15)
				(type solid)
			)
			(fill yes)
			(layer "F.SilkS")
		)
		(fp_rect
			(start -2.05 -3.95)
			(end 2.05 3.95)
			(stroke
				(width 0.05)
				(type solid)
			)
			(fill no)
			(layer "F.CrtYd")
		)
		(fp_rect
			(start -1.8 -3)
			(end 1.8 3)
			(stroke
				(width 0.15)
				(type solid)
			)
			(fill no)
			(layer "F.Fab")
		)
		(fp_text user "License: Apache-2.0"
			(at -3.25 9.4 0)
			(layer "F.Fab")
			(effects
				(font
					(size 0.7 0.7)
					(thickness 0.15)
				)
				(justify right top)
			)
		)
		(fp_text user "Author: Antmicro"
			(at -3.25 7 0)
			(layer "F.Fab")
			(effects
				(font
					(size 0.7 0.7)
					(thickness 0.15)
				)
				(justify right top)
			)
		)
		(fp_text user "${REFERENCE}"
			(at -3.25 8.2 0)
			(layer "F.Fab")
			(effects
				(font
					(size 0.7 0.7)
					(thickness 0.15)
				)
				(justify right top)
			)
		)
		(pad "1" smd roundrect
			(at -1.45 -1.5 90)
			(size 0.6 1.55)
			(layers "F.Cu" "F.Mask" "F.Paste")
			(roundrect_rratio 0.25)
			(net 1 "GND")
			(pintype "passive")
		)
		(pad "2" smd roundrect
			(at -1.45 -0.5 90)
			(size 0.6 1.55)
			(layers "F.Cu" "F.Mask" "F.Paste")
			(roundrect_rratio 0.25)
			(net 495 "/SoM_Power/~{FORCE_RECOVERY}")
			(pintype "passive")
		)
		(pad "3" smd roundrect
			(at -1.45 0.5 90)
			(size 0.6 1.55)
			(layers "F.Cu" "F.Mask" "F.Paste")
			(roundrect_rratio 0.25)
			(net 702 "/SoM_Power/~{SYS_RESET}")
			(pintype "passive")
		)
		(pad "4" smd roundrect
			(at -1.45 1.5 90)
			(size 0.6 1.55)
			(layers "F.Cu" "F.Mask" "F.Paste")
			(roundrect_rratio 0.25)
			(net 610 "/SoM_Power/~{PWR_BTN}")
			(pintype "passive")
		)
		(pad "MP" smd roundrect
			(at 1.075 -2.8 90)
			(size 1.2 1.8)
			(layers "F.Cu" "F.Mask" "F.Paste")
			(roundrect_rratio 0.25)
			(net 1 "GND")
			(pintype "passive")
		)
		(pad "MP" smd roundrect
			(at 1.075 2.8 90)
			(size 1.2 1.8)
			(layers "F.Cu" "F.Mask" "F.Paste")
			(roundrect_rratio 0.25)
			(net 1 "GND")
			(pintype "passive")
		)
	)
	(footprint "antmicro-footprints:R_0402_1005Metric"
		(layer "F.Cu")
		(at 210.114132 94.642 180)
		(descr "Resistor SMD 0402")
		(tags "resistor SMD 0402")
		(property "Reference" "R121"
			(at 0.914132 -0.558 0)
			(layer "F.SilkS")
			(effects
				(font
					(size 0.7 0.7)
					(thickness 0.15)
				)
				(justify right top)
			)
		)
		(property "Value" "R_0R_0402"
			(at -1.011843 1.772047 0)
			(layer "F.Fab")
			(effects
				(font
					(size 0.7 0.7)
					(thickness 0.15)
				)
				(justify right top)
			)
		)
		(property "Datasheet" "https://industrial.panasonic.com/cdbs/www-data/pdf/RDA0000/AOA0000C301.pdf"
			(at 0 0 0)
			(layer "F.Fab")
			(hide yes)
			(effects
				(font
					(size 1.27 1.27)
					(thickness 0.15)
				)
			)
		)
		(property "Description" "SMD Chip Resistor, Jumper, 0 ohm, 100 mW, 0402 [1005 Metric], Thick Film, General Purpose"
			(at 0 0 0)
			(layer "F.Fab")
			(hide yes)
			(effects
				(font
					(size 1.27 1.27)
					(thickness 0.15)
				)
			)
		)
		(property "Manufacturer" "Panasonic"
			(at 0 0 180)
			(unlocked yes)
			(layer "F.Fab")
			(hide yes)
			(effects
				(font
					(size 1 1)
					(thickness 0.15)
				)
			)
		)
		(property "MPN" "ERJ2GE0R00X"
			(at 0 0 180)
			(unlocked yes)
			(layer "F.Fab")
			(hide yes)
			(effects
				(font
					(size 1 1)
					(thickness 0.15)
				)
			)
		)
		(property "Val" "0R"
			(at 0 0 180)
			(unlocked yes)
			(layer "F.Fab")
			(hide yes)
			(effects
				(font
					(size 1 1)
					(thickness 0.15)
				)
			)
		)
		(property "License" "Apache-2.0"
			(at 0 0 180)
			(unlocked yes)
			(layer "F.Fab")
			(hide yes)
			(effects
				(font
					(size 1 1)
					(thickness 0.15)
				)
			)
		)
		(property "Author" "Antmicro"
			(at 0 0 180)
			(unlocked yes)
			(layer "F.Fab")
			(hide yes)
			(effects
				(font
					(size 1 1)
					(thickness 0.15)
				)
			)
		)
		(property "Tolerance" "~"
			(at 0 0 180)
			(unlocked yes)
			(layer "F.Fab")
			(hide yes)
			(effects
				(font
					(size 1 1)
					(thickness 0.15)
				)
			)
		)
		(property "Current" "1A"
			(at 0 0 180)
			(unlocked yes)
			(layer "F.Fab")
			(hide yes)
			(effects
				(font
					(size 1 1)
					(thickness 0.15)
				)
			)
		)
		(sheetname "/USB DP Alt mode/")
		(sheetfile "usb_dp.kicad_sch")
		(attr smd exclude_from_pos_files exclude_from_bom dnp)
		(fp_rect
			(start -0.925 -0.47)
			(end 0.925 0.47)
			(stroke
				(width 0.05)
				(type default)
			)
			(fill no)
			(layer "F.CrtYd")
		)
		(fp_rect
			(start -0.5 -0.25)
			(end 0.5 0.25)
			(stroke
				(width 0.15)
				(type solid)
			)
			(fill no)
			(layer "F.Fab")
		)
		(fp_text user "${REFERENCE}"
			(at -0.95 3.168 0)
			(layer "F.Fab")
			(effects
				(font
					(size 0.7 0.7)
					(thickness 0.15)
				)
				(justify right top)
			)
		)
		(fp_text user "Author: Antmicro"
			(at -0.95 4.169 0)
			(layer "F.Fab")
			(effects
				(font
					(size 0.7 0.7)
					(thickness 0.15)
				)
				(justify right top)
			)
		)
		(fp_text user "License: Apache-2.0"
			(at -0.95 5.169 0)
			(layer "F.Fab")
			(effects
				(font
					(size 0.7 0.7)
					(thickness 0.15)
				)
				(justify right top)
			)
		)
		(pad "1" smd roundrect
			(at -0.48 0 180)
			(size 0.59 0.64)
			(layers "F.Cu" "F.Mask" "F.Paste")
			(roundrect_rratio 0.25)
			(net 943 "/USB DP Alt mode/USBC1_CTL0")
			(pintype "passive")
		)
		(pad "2" smd roundrect
			(at 0.48 0 180)
			(size 0.59 0.64)
			(layers "F.Cu" "F.Mask" "F.Paste")
			(roundrect_rratio 0.25)
			(net 850 "/I2C_{SYS}.SDA")
			(pintype "passive")
		)
	)
	(footprint "antmicro-footprints:C_0402_1005Metric"
		(layer "F.Cu")
		(at 213.5 123.68 180)
		(descr "Capacitor SMD 0402")
		(tags "capacitor SMD 0402")
		(property "Reference" "C99"
			(at -1.1 1.28 0)
			(layer "F.SilkS")
			(effects
				(font
					(size 0.7 0.7)
					(thickness 0.15)
				)
				(justify right top)
			)
		)
		(property "Value" "C_100n_0402"
			(at -1.022927 2.155213 0)
			(layer "F.Fab")
			(effects
				(font
					(size 0.7 0.7)
					(thickness 0.15)
				)
				(justify right top)
			)
		)
		(property "Datasheet" "https://www.murata.com/products/productdetail?partno=GRM155R61H104KE14%23"
			(at 0 0 0)
			(layer "F.Fab")
			(hide yes)
			(effects
				(font
					(size 1.27 1.27)
					(thickness 0.15)
				)
			)
		)
		(property "Description" "SMD Multilayer Ceramic Capacitor, 0.1 µF, 50 V, 0402 [1005 Metric], ± 10%, X5R, GRM Series"
			(at 0 0 0)
			(layer "F.Fab")
			(hide yes)
			(effects
				(font
					(size 1.27 1.27)
					(thickness 0.15)
				)
			)
		)
		(property "MPN" "GRM155R61H104KE14D"
			(at 0 0 180)
			(unlocked yes)
			(layer "F.Fab")
			(hide yes)
			(effects
				(font
					(size 1 1)
					(thickness 0.15)
				)
			)
		)
		(property "Val" "100n"
			(at 0 0 180)
			(unlocked yes)
			(layer "F.Fab")
			(hide yes)
			(effects
				(font
					(size 1 1)
					(thickness 0.15)
				)
			)
		)
		(property "Voltage" "50V"
			(at 0 0 180)
			(unlocked yes)
			(layer "F.Fab")
			(hide yes)
			(effects
				(font
					(size 1 1)
					(thickness 0.15)
				)
			)
		)
		(property "Dielectric" "X5R"
			(at 0 0 180)
			(unlocked yes)
			(layer "F.Fab")
			(hide yes)
			(effects
				(font
					(size 1 1)
					(thickness 0.15)
				)
			)
		)
		(property "Manufacturer" "Murata"
			(at 0 0 180)
			(unlocked yes)
			(layer "F.Fab")
			(hide yes)
			(effects
				(font
					(size 1 1)
					(thickness 0.15)
				)
			)
		)
		(property "License" "Apache-2.0"
			(at 0 0 180)
			(unlocked yes)
			(layer "F.Fab")
			(hide yes)
			(effects
				(font
					(size 1 1)
					(thickness 0.15)
				)
			)
		)
		(property "Author" "Antmicro"
			(at 0 0 180)
			(unlocked yes)
			(layer "F.Fab")
			(hide yes)
			(effects
				(font
					(size 1 1)
					(thickness 0.15)
				)
			)
		)
		(sheetname "/USB Hub/")
		(sheetfile "usb_hub.kicad_sch")
		(attr smd)
		(fp_poly
			(pts
				(xy -0.925 -0.47) (xy 0.925 -0.47) (xy 0.925 0.47) (xy -0.925 0.47)
			)
			(stroke
				(width 0.05)
				(type default)
			)
			(fill no)
			(layer "F.CrtYd")
		)
		(fp_line
			(start 0.504 0.248)
			(end -0.494 0.248)
			(stroke
				(width 0.15)
				(type solid)
			)
			(layer "F.Fab")
		)
		(fp_line
			(start 0.504 -0.25)
			(end 0.504 0.248)
			(stroke
				(width 0.15)
				(type solid)
			)
			(layer "F.Fab")
		)
		(fp_line
			(start -0.494 0.248)
			(end -0.494 -0.25)
			(stroke
				(width 0.15)
				(type solid)
			)
			(layer "F.Fab")
		)
		(fp_line
			(start -0.494 -0.25)
			(end 0.504 -0.25)
			(stroke
				(width 0.15)
				(type solid)
			)
			(layer "F.Fab")
		)
		(fp_text user "${REFERENCE}"
			(at -0.939 4.599 0)
			(layer "F.Fab")
			(effects
				(font
					(size 0.7 0.7)
					(thickness 0.15)
				)
				(justify right top)
			)
		)
		(fp_text user "Author: Antmicro"
			(at -0.939 3.399 0)
			(layer "F.Fab")
			(effects
				(font
					(size 0.7 0.7)
					(thickness 0.15)
				)
				(justify right top)
			)
		)
		(fp_text user "License: Apache-2.0"
			(at -0.939 5.799 0)
			(layer "F.Fab")
			(effects
				(font
					(size 0.7 0.7)
					(thickness 0.15)
				)
				(justify right top)
			)
		)
		(pad "1" smd roundrect
			(at -0.48 0 180)
			(size 0.59 0.64)
			(layers "F.Cu" "F.Mask" "F.Paste")
			(roundrect_rratio 0.25)
			(net 1 "GND")
			(pintype "passive")
		)
		(pad "2" smd roundrect
			(at 0.48 0 180)
			(size 0.59 0.64)
			(layers "F.Cu" "F.Mask" "F.Paste")
			(roundrect_rratio 0.25)
			(net 282 "+1V15")
			(pintype "passive")
		)
	)
)
